# BASEBOARD_FAB2 (Tioga Pass) — schematic netlist excerpt (pin names and nets, part order shuffled) for the footprints in the layout excerpt that follows; sources: Cadence DE-HDL packaged netlist, KiCad conversion of Wiwynn_Tioga_Pass_MB.brd

C5T10  CAP_A  47UF 4V 20% X5R  pkg 0603V  page 217 : A = PVDDQ_ABC ; B = GND
R9P30  RES  10.0 1% CHIP  pkg 0603  page 199 : A = P12V_PSU ; B = P12V_HSC_VCC
C2T14  CAP  0.22UF 16V 10% X7R  pkg 0402  page 185 : A = P3E_PCH_M2_TX_C_DN<2> ; B = P3E_PCH_M2_TX_DN<2>

(kicad_pcb
	(version 20260206)
	(generator "pcbnew")
	(generator_version "10.0")
	(general
		(thickness 1.6)
		(legacy_teardrops no)
	)
	(paper "A4")
	(title_block
		(title "Wiwynn_Tioga_Pass_MB.brd")
		(comment 1 "Tioga Pass / footprints 4161-4163 of 4770")
	)
	(layers
		(0 "F.Cu" signal "TOP")
		(4 "In1.Cu" signal "L2GND")
		(6 "In2.Cu" signal "L3")
		(8 "In3.Cu" signal "L4GND")
		(10 "In4.Cu" signal "L5")
		(12 "In5.Cu" signal "L6GND")
		(14 "In6.Cu" signal "L7VCC")
		(16 "In7.Cu" signal "L8VCC")
		(18 "In8.Cu" signal "L9GND")
		(20 "In9.Cu" signal "L10")
		(22 "In10.Cu" signal "L11GND")
		(24 "In11.Cu" signal "L12")
		(26 "In12.Cu" signal "L13GND")
		(2 "B.Cu" signal "BOTTOM")
		(9 "F.Adhes" user "F.Adhesive")
		(11 "B.Adhes" user "B.Adhesive")
		(13 "F.Paste" user "Package Geometry/Pastemask Top")
		(15 "B.Paste" user "Package Geometry/Pastemask Bottom")
		(5 "F.SilkS" user "Ref Des/Silkscreen Top")
		(7 "B.SilkS" user "Ref Des/Silkscreen Bottom")
		(1 "F.Mask" user "Board Geometry/Soldermask Top")
		(3 "B.Mask" user "Board Geometry/Soldermask Bottom")
		(17 "Dwgs.User" user "User.Drawings")
		(19 "Cmts.User" user "User.Comments")
		(21 "Eco1.User" user "User.Eco1")
		(23 "Eco2.User" user "User.Eco2")
		(25 "Edge.Cuts" user "Board Geometry/Outline")
		(27 "Margin" user)
		(31 "F.CrtYd" user "Package Geometry/Place Bound Top")
		(29 "B.CrtYd" user "Package Geometry/Place Bound Bottom")
		(35 "F.Fab" user "Ref Des/Assembly Top")
		(33 "B.Fab" user "Ref Des/Assembly Bottom")
	)
	(footprint ""
		(layer "B.Cu")
		(at 19.177 -69.596 180)
		(property "Reference" "R9P30"
			(at 0 0 0)
			(layer "B.SilkS")
			(hide yes)
			(effects
				(font
					(size 1.27 1.27)
				)
				(justify mirror)
			)
		)
		(property "Value" ""
			(at 0 0 0)
			(layer "B.Fab")
			(effects
				(font
					(size 1.27 1.27)
				)
				(justify mirror)
			)
		)
		(duplicate_pad_numbers_are_jumpers no)
		(fp_rect
			(start -0.4953 -0.2032)
			(end 0.4953 1.6002)
			(stroke
				(width 0)
				(type default)
			)
			(fill no)
			(layer "B.CrtYd")
		)
		(fp_line
			(start 0.4953 1.6002)
			(end 0.4953 -0.2032)
			(stroke
				(width 0.1)
				(type default)
			)
			(layer "B.Fab")
		)
		(fp_line
			(start 0.4953 -0.2032)
			(end -0.4953 -0.2032)
			(stroke
				(width 0.1)
				(type default)
			)
			(layer "B.Fab")
		)
		(fp_line
			(start -0.4953 1.6002)
			(end 0.4953 1.6002)
			(stroke
				(width 0.1)
				(type default)
			)
			(layer "B.Fab")
		)
		(fp_line
			(start -0.4953 -0.2032)
			(end -0.4953 1.6002)
			(stroke
				(width 0.1)
				(type default)
			)
			(layer "B.Fab")
		)
		(pad "1" smd rect
			(at 0 0)
			(size 0.762 0.889)
			(layers "B.Cu" "B.Mask" "B.Paste")
			(net "P12V_PSU")
		)
		(pad "2" smd rect
			(at 0 1.397)
			(size 0.762 0.889)
			(layers "B.Cu" "B.Mask" "B.Paste")
			(net "P12V_HSC_VCC")
		)
		(zone
			(layer "B.Cu")
			(hatch none 0.5)
			(connect_pads
				(clearance 0)
			)
			(min_thickness 0.25)
			(keepout
				(tracks not_allowed)
				(vias allowed)
				(pads allowed)
				(copperpour not_allowed)
				(footprints allowed)
			)
			(placement
				(enabled no)
				(sheetname "")
			)
			(fill
				(thermal_gap 0.5)
				(thermal_bridge_width 0.5)
				(island_removal_mode 0)
			)
			(polygon
				(pts
					(xy 19.558 -70.0405) (xy 19.558 -70.5485) (xy 18.796 -70.5485) (xy 18.796 -70.0405)
				)
			)
		)
		(zone
			(layer "B.Cu")
			(hatch none 0.5)
			(connect_pads
				(clearance 0)
			)
			(min_thickness 0.25)
			(keepout
				(tracks allowed)
				(vias not_allowed)
				(pads allowed)
				(copperpour not_allowed)
				(footprints allowed)
			)
			(placement
				(enabled no)
				(sheetname "")
			)
			(fill
				(thermal_gap 0.5)
				(thermal_bridge_width 0.5)
				(island_removal_mode 0)
			)
			(polygon
				(pts
					(xy 19.558 -70.0405) (xy 19.558 -70.5485) (xy 18.796 -70.5485) (xy 18.796 -70.0405)
				)
			)
		)
	)
	(footprint ""
		(layer "B.Cu")
		(at 385.463034 -26.506932 90)
		(property "Reference" "C2T14"
			(at 0 0 90)
			(layer "B.SilkS")
			(hide yes)
			(effects
				(font
					(size 1.27 1.27)
				)
				(justify mirror)
			)
		)
		(property "Value" ""
			(at 0 0 90)
			(layer "B.Fab")
			(effects
				(font
					(size 1.27 1.27)
				)
				(justify mirror)
			)
		)
		(duplicate_pad_numbers_are_jumpers no)
		(fp_poly
			(pts
				(xy -0.3048 -0.1016) (xy -0.3048 0.9906) (xy 0.3048 0.9906) (xy 0.3048 -0.1016)
			)
			(stroke
				(width 0)
				(type default)
			)
			(fill no)
			(layer "B.CrtYd")
		)
		(fp_line
			(start 0.3048 -0.1016)
			(end 0.3048 0.9906)
			(stroke
				(width 0.1)
				(type default)
			)
			(layer "B.Fab")
		)
		(fp_line
			(start -0.3048 -0.1016)
			(end 0.3048 -0.1016)
			(stroke
				(width 0.1)
				(type default)
			)
			(layer "B.Fab")
		)
		(fp_line
			(start 0.3048 0.9906)
			(end -0.3048 0.9906)
			(stroke
				(width 0.1)
				(type default)
			)
			(layer "B.Fab")
		)
		(fp_line
			(start -0.3048 0.9906)
			(end -0.3048 -0.1016)
			(stroke
				(width 0.1)
				(type default)
			)
			(layer "B.Fab")
		)
		(pad "1" smd rect
			(at 0 0 270)
			(size 0.508 0.508)
			(layers "B.Cu" "B.Mask" "B.Paste")
			(net "P3E_PCH_M2_TX_C_DN<2>")
		)
		(pad "2" smd rect
			(at 0 0.889 270)
			(size 0.508 0.508)
			(layers "B.Cu" "B.Mask" "B.Paste")
			(net "P3E_PCH_M2_TX_DN<2>")
		)
		(zone
			(layer "B.Cu")
			(hatch none 0.5)
			(connect_pads
				(clearance 0)
			)
			(min_thickness 0.25)
			(keepout
				(tracks allowed)
				(vias not_allowed)
				(pads allowed)
				(copperpour not_allowed)
				(footprints allowed)
			)
			(placement
				(enabled no)
				(sheetname "")
			)
			(fill
				(thermal_gap 0.5)
				(thermal_bridge_width 0.5)
				(island_removal_mode 0)
			)
			(polygon
				(pts
					(xy 385.717034 -26.760932) (xy 385.717034 -26.252932) (xy 386.098034 -26.252932) (xy 386.098034 -26.760932)
				)
			)
		)
		(zone
			(layer "B.Cu")
			(hatch none 0.5)
			(connect_pads
				(clearance 0)
			)
			(min_thickness 0.25)
			(keepout
				(tracks not_allowed)
				(vias allowed)
				(pads allowed)
				(copperpour not_allowed)
				(footprints allowed)
			)
			(placement
				(enabled no)
				(sheetname "")
			)
			(fill
				(thermal_gap 0.5)
				(thermal_bridge_width 0.5)
				(island_removal_mode 0)
			)
			(polygon
				(pts
					(xy 386.098034 -26.760932) (xy 386.098034 -26.252932) (xy 385.717034 -26.252932) (xy 385.717034 -26.760932)
				)
			)
		)
	)
	(footprint ""
		(layer "B.Cu")
		(at 252.1585 -17.7546 -90)
		(property "Reference" "C5T10"
			(at -1.848866 0.752348 270)
			(unlocked yes)
			(layer "B.SilkS")
			(effects
				(font
					(size 1.27 0.9652)
					(thickness 0.1524)
				)
				(justify mirror)
			)
		)
		(property "Value" ""
			(at 0 0 90)
			(layer "B.Fab")
			(effects
				(font
					(size 1.27 1.27)
				)
				(justify mirror)
			)
		)
		(duplicate_pad_numbers_are_jumpers no)
		(fp_rect
			(start 0.500126 1.598422)
			(end -0.500126 -0.201422)
			(stroke
				(width 0)
				(type default)
			)
			(fill no)
			(layer "B.CrtYd")
		)
		(fp_line
			(start -0.500126 1.598422)
			(end 0.500126 1.598422)
			(stroke
				(width 0.1)
				(type default)
			)
			(layer "B.Fab")
		)
		(fp_line
			(start 0.500126 1.598422)
			(end 0.500126 -0.201422)
			(stroke
				(width 0.1)
				(type default)
			)
			(layer "B.Fab")
		)
		(fp_line
			(start -0.500126 -0.201422)
			(end -0.500126 1.598422)
			(stroke
				(width 0.1)
				(type default)
			)
			(layer "B.Fab")
		)
		(fp_line
			(start 0.500126 -0.201422)
			(end -0.500126 -0.201422)
			(stroke
				(width 0.1)
				(type default)
			)
			(layer "B.Fab")
		)
		(pad "1" smd rect
			(at 0 0 180)
			(size 0.889 0.9906)
			(layers "B.Cu" "B.Mask" "B.Paste")
			(net "PVDDQ_ABC")
		)
		(pad "2" smd rect
			(at 0 1.397 180)
			(size 0.889 0.9906)
			(layers "B.Cu" "B.Mask" "B.Paste")
			(net "GND")
		)
		(zone
			(layer "B.Cu")
			(hatch none 0.5)
			(connect_pads
				(clearance 0)
			)
			(min_thickness 0.25)
			(keepout
				(tracks not_allowed)
				(vias allowed)
				(pads allowed)
				(copperpour not_allowed)
				(footprints allowed)
			)
			(placement
				(enabled no)
				(sheetname "")
			)
			(fill
				(thermal_gap 0.5)
				(thermal_bridge_width 0.5)
				(island_removal_mode 0)
			)
			(polygon
				(pts
					(xy 251.206 -17.2593) (xy 251.714 -17.2593) (xy 251.714 -18.2499) (xy 251.206 -18.2499)
				)
			)
		)
		(zone
			(layer "B.Cu")
			(hatch none 0.5)
			(connect_pads
				(clearance 0)
			)
			(min_thickness 0.25)
			(keepout
				(tracks allowed)
				(vias not_allowed)
				(pads allowed)
				(copperpour not_allowed)
				(footprints allowed)
			)
			(placement
				(enabled no)
				(sheetname "")
			)
			(fill
				(thermal_gap 0.5)
				(thermal_bridge_width 0.5)
				(island_removal_mode 0)
			)
			(polygon
				(pts
					(xy 251.206 -17.2593) (xy 251.714 -17.2593) (xy 251.714 -18.2499) (xy 251.206 -18.2499)
				)
			)
		)
	)
)
